(kicad_pcb
	(version 20260206)
	(generator "pcbnew")
	(generator_version "10.0")
	(general
		(thickness 1.6)
		(legacy_teardrops no)
	)
	(paper "A4")
	(title_block
		(title "Bryce Canyon_IOM_IOC_16318-2_OCP.brd")
		(comment 1 "Bryce Canyon / footprints 1333-1339 of 1605")
	)
	(layers
		(0 "F.Cu" signal "TOP")
		(4 "In1.Cu" signal "L2GND")
		(6 "In2.Cu" signal "L3")
		(8 "In3.Cu" signal "L4VCC")
		(10 "In4.Cu" signal "L5VCC")
		(12 "In5.Cu" signal "L6")
		(14 "In6.Cu" signal "L7GND")
		(2 "B.Cu" signal "BOTTOM")
		(9 "F.Adhes" user "F.Adhesive")
		(11 "B.Adhes" user "B.Adhesive")
		(13 "F.Paste" user "Package Geometry/Pastemask Top")
		(15 "B.Paste" user "Package Geometry/Pastemask Bottom")
		(5 "F.SilkS" user "Ref Des/Silkscreen Top")
		(7 "B.SilkS" user "Ref Des/Silkscreen Bottom")
		(1 "F.Mask" user "Board Geometry/Soldermask Top")
		(3 "B.Mask" user "Board Geometry/Soldermask Bottom")
		(17 "Dwgs.User" user "User.Drawings")
		(19 "Cmts.User" user "User.Comments")
		(21 "Eco1.User" user "User.Eco1")
		(23 "Eco2.User" user "User.Eco2")
		(25 "Edge.Cuts" user "Board Geometry/Outline")
		(27 "Margin" user)
		(31 "F.CrtYd" user "Package Geometry/Place Bound Top")
		(29 "B.CrtYd" user "Package Geometry/Place Bound Bottom")
		(35 "F.Fab" user "Ref Des/Assembly Top")
		(33 "B.Fab" user "Ref Des/Assembly Bottom")
	)
	(footprint ""
		(layer "B.Cu")
		(at 13.323824 -145.23593 90)
		(property "Reference" "R209"
			(at 0 0 90)
			(layer "B.SilkS")
			(hide yes)
			(effects
				(font
					(size 1.27 1.27)
				)
				(justify mirror)
			)
		)
		(property "Value" "120R2F-GP"
			(at -0.064008 -3.993896 90)
			(unlocked yes)
			(layer "B.Fab")
			(hide yes)
			(effects
				(font
					(size 1.016 1.016)
					(thickness 0.1524)
				)
				(justify mirror)
			)
		)
		(property "Device Type" "R402H16"
			(at -0.064008 -5.517896 90)
			(unlocked yes)
			(layer "B.Fab")
			(hide yes)
			(effects
				(font
					(size 1.016 1.016)
					(thickness 0.1524)
				)
				(justify mirror)
			)
		)
		(duplicate_pad_numbers_are_jumpers no)
		(fp_line
			(start 0.508 -0.9398)
			(end 0.508 0.9398)
			(stroke
				(width 0.1524)
				(type default)
			)
			(layer "B.SilkS")
		)
		(fp_line
			(start -0.508 -0.9398)
			(end 0.508 -0.9398)
			(stroke
				(width 0.1524)
				(type default)
			)
			(layer "B.SilkS")
		)
		(fp_rect
			(start 0.508 0.9398)
			(end -0.508 -0.9398)
			(stroke
				(width 0)
				(type default)
			)
			(fill no)
			(layer "B.CrtYd")
		)
		(fp_rect
			(start 0.508 0.9398)
			(end -0.508 -0.9398)
			(stroke
				(width 0)
				(type default)
			)
			(fill no)
			(layer "B.Fab")
		)
		(pad "1" smd custom
			(at 0 -0.4445 270)
			(size 0.1397 0.1397)
			(layers "B.Cu" "B.Mask" "B.Paste")
			(net "GND")
			(options
				(clearance outline)
				(anchor circle)
			)
			(primitives
				(gr_poly
					(pts
						(arc
							(start -0.1778 0.2794)
							(mid -0.249642 0.249642)
							(end -0.2794 0.1778)
						)
						(arc
							(start -0.2794 -0.1778)
							(mid -0.249642 -0.249642)
							(end -0.1778 -0.2794)
						)
						(arc
							(start 0.1778 -0.2794)
							(mid 0.249642 -0.249642)
							(end 0.2794 -0.1778)
						)
						(arc
							(start 0.2794 0.1778)
							(mid 0.249642 0.249642)
							(end 0.1778 0.2794)
						)
					)
					(width 0)
					(fill yes)
				)
			)
		)
		(pad "2" smd custom
			(at 0 0.4445 270)
			(size 0.1397 0.1397)
			(layers "B.Cu" "B.Mask" "B.Paste")
			(net "MEMCKE")
			(options
				(clearance outline)
				(anchor circle)
			)
			(primitives
				(gr_poly
					(pts
						(arc
							(start -0.1778 0.2794)
							(mid -0.249642 0.249642)
							(end -0.2794 0.1778)
						)
						(arc
							(start -0.2794 -0.1778)
							(mid -0.249642 -0.249642)
							(end -0.1778 -0.2794)
						)
						(arc
							(start 0.1778 -0.2794)
							(mid 0.249642 -0.249642)
							(end 0.2794 -0.1778)
						)
						(arc
							(start 0.2794 0.1778)
							(mid 0.249642 0.249642)
							(end 0.1778 0.2794)
						)
					)
					(width 0)
					(fill yes)
				)
			)
		)
	)
	(footprint ""
		(layer "B.Cu")
		(at 45.07484 -154.29992 -90)
		(property "Reference" "C105"
			(at 0 0 90)
			(layer "B.SilkS")
			(hide yes)
			(effects
				(font
					(size 1.27 1.27)
				)
				(justify mirror)
			)
		)
		(property "Value" "SC100P50V2JN-3GP"
			(at -1.1811 -2.7051 270)
			(unlocked yes)
			(layer "B.Fab")
			(hide yes)
			(effects
				(font
					(size 1.016 1.016)
					(thickness 0.1524)
				)
				(justify mirror)
			)
		)
		(property "Device Type" "C402H22"
			(at -1.1811 -4.2291 270)
			(unlocked yes)
			(layer "B.Fab")
			(hide yes)
			(effects
				(font
					(size 1.016 1.016)
					(thickness 0.1524)
				)
				(justify mirror)
			)
		)
		(duplicate_pad_numbers_are_jumpers no)
		(fp_rect
			(start 0.4318 0.9525)
			(end -0.4318 -0.9525)
			(stroke
				(width 0)
				(type default)
			)
			(fill no)
			(layer "B.CrtYd")
		)
		(fp_rect
			(start 0.4318 0.9525)
			(end -0.4318 -0.9525)
			(stroke
				(width 0)
				(type default)
			)
			(fill no)
			(layer "B.Fab")
		)
		(pad "1" smd custom
			(at 0 -0.4445 90)
			(size 0.1524 0.1524)
			(layers "B.Cu" "B.Mask" "B.Paste")
			(net "V1PLLAV11")
			(options
				(clearance outline)
				(anchor circle)
			)
			(primitives
				(gr_poly
					(pts
						(arc
							(start 0.3048 0.2032)
							(mid 0.275042 0.275042)
							(end 0.2032 0.3048)
						)
						(arc
							(start -0.2032 0.3048)
							(mid -0.275042 0.275042)
							(end -0.3048 0.2032)
						)
						(arc
							(start -0.3048 -0.2032)
							(mid -0.275042 -0.275042)
							(end -0.2032 -0.3048)
						)
						(arc
							(start 0.2032 -0.3048)
							(mid 0.275042 -0.275042)
							(end 0.3048 -0.2032)
						)
					)
					(width 0)
					(fill yes)
				)
			)
		)
		(pad "2" smd custom
			(at 0 0.4445 90)
			(size 0.1524 0.1524)
			(layers "B.Cu" "B.Mask" "B.Paste")
			(net "GND")
			(options
				(clearance outline)
				(anchor circle)
			)
			(primitives
				(gr_poly
					(pts
						(arc
							(start 0.3048 0.2032)
							(mid 0.275042 0.275042)
							(end 0.2032 0.3048)
						)
						(arc
							(start -0.2032 0.3048)
							(mid -0.275042 0.275042)
							(end -0.3048 0.2032)
						)
						(arc
							(start -0.3048 -0.2032)
							(mid -0.275042 -0.275042)
							(end -0.2032 -0.3048)
						)
						(arc
							(start 0.2032 -0.3048)
							(mid 0.275042 -0.275042)
							(end 0.3048 -0.2032)
						)
					)
					(width 0)
					(fill yes)
				)
			)
		)
	)
	(footprint ""
		(layer "B.Cu")
		(at 191.68999 -23.876 -90)
		(property "Reference" "C492"
			(at 0 0 90)
			(layer "B.SilkS")
			(hide yes)
			(effects
				(font
					(size 1.27 1.27)
				)
				(justify mirror)
			)
		)
		(property "Value" "SCD01U16V1KX-GP"
			(at 2.8321 -1.7399 270)
			(unlocked yes)
			(layer "B.Fab")
			(hide yes)
			(effects
				(font
					(size 1.016 1.016)
					(thickness 0.1524)
				)
				(justify mirror)
			)
		)
		(property "Device Type" "C0201H13"
			(at 2.8321 -3.2639 270)
			(unlocked yes)
			(layer "B.Fab")
			(hide yes)
			(effects
				(font
					(size 1.016 1.016)
					(thickness 0.1524)
				)
				(justify mirror)
			)
		)
		(duplicate_pad_numbers_are_jumpers no)
		(fp_rect
			(start 0.2794 0.6477)
			(end -0.2794 -0.6477)
			(stroke
				(width 0)
				(type default)
			)
			(fill no)
			(layer "B.CrtYd")
		)
		(fp_rect
			(start 0.2794 0.6477)
			(end -0.2794 -0.6477)
			(stroke
				(width 0)
				(type default)
			)
			(fill no)
			(layer "B.Fab")
		)
		(pad "1" smd custom
			(at 0 -0.2794 90)
			(size 0.0762 0.0762)
			(layers "B.Cu" "B.Mask" "B.Paste")
			(net "PHY_CON_A_TO_IOC_2_DP")
			(options
				(clearance outline)
				(anchor circle)
			)
			(primitives
				(gr_poly
					(pts
						(arc
							(start 0.1524 0.127)
							(mid 0.137521 0.162921)
							(end 0.1016 0.1778)
						)
						(arc
							(start -0.1016 0.1778)
							(mid -0.137521 0.162921)
							(end -0.1524 0.127)
						)
						(arc
							(start -0.1524 -0.127)
							(mid -0.137521 -0.162921)
							(end -0.1016 -0.1778)
						)
						(arc
							(start 0.1016 -0.1778)
							(mid 0.137521 -0.162921)
							(end 0.1524 -0.127)
						)
					)
					(width 0)
					(fill yes)
				)
			)
		)
		(pad "2" smd custom
			(at 0 0.2794 90)
			(size 0.0762 0.0762)
			(layers "B.Cu" "B.Mask" "B.Paste")
			(net "PHY_CON_A_TO_IOC_2_DP_C")
			(options
				(clearance outline)
				(anchor circle)
			)
			(primitives
				(gr_poly
					(pts
						(arc
							(start 0.1524 0.127)
							(mid 0.137521 0.162921)
							(end 0.1016 0.1778)
						)
						(arc
							(start -0.1016 0.1778)
							(mid -0.137521 0.162921)
							(end -0.1524 0.127)
						)
						(arc
							(start -0.1524 -0.127)
							(mid -0.137521 -0.162921)
							(end -0.1016 -0.1778)
						)
						(arc
							(start 0.1016 -0.1778)
							(mid 0.137521 -0.162921)
							(end 0.1524 -0.127)
						)
					)
					(width 0)
					(fill yes)
				)
			)
		)
	)
	(footprint ""
		(layer "B.Cu")
		(at 62.865 -153.99004 -90)
		(property "Reference" "R303"
			(at 0 0 90)
			(layer "B.SilkS")
			(hide yes)
			(effects
				(font
					(size 1.27 1.27)
				)
				(justify mirror)
			)
		)
		(property "Value" "47KR2F-GP"
			(at -0.064008 -3.993896 270)
			(unlocked yes)
			(layer "B.Fab")
			(hide yes)
			(effects
				(font
					(size 1.016 1.016)
					(thickness 0.1524)
				)
				(justify mirror)
			)
		)
		(property "Device Type" "R402H16"
			(at -0.064008 -5.517896 270)
			(unlocked yes)
			(layer "B.Fab")
			(hide yes)
			(effects
				(font
					(size 1.016 1.016)
					(thickness 0.1524)
				)
				(justify mirror)
			)
		)
		(duplicate_pad_numbers_are_jumpers no)
		(fp_line
			(start -0.508 -0.9398)
			(end 0.508 -0.9398)
			(stroke
				(width 0.1524)
				(type default)
			)
			(layer "B.SilkS")
		)
		(fp_line
			(start 0.508 -0.9398)
			(end 0.508 0.9398)
			(stroke
				(width 0.1524)
				(type default)
			)
			(layer "B.SilkS")
		)
		(fp_rect
			(start 0.508 0.9398)
			(end -0.508 -0.9398)
			(stroke
				(width 0)
				(type default)
			)
			(fill no)
			(layer "B.CrtYd")
		)
		(fp_rect
			(start 0.508 0.9398)
			(end -0.508 -0.9398)
			(stroke
				(width 0)
				(type default)
			)
			(fill no)
			(layer "B.Fab")
		)
		(pad "1" smd custom
			(at 0 -0.4445 90)
			(size 0.1397 0.1397)
			(layers "B.Cu" "B.Mask" "B.Paste")
			(net "GND")
			(options
				(clearance outline)
				(anchor circle)
			)
			(primitives
				(gr_poly
					(pts
						(arc
							(start -0.1778 0.2794)
							(mid -0.249642 0.249642)
							(end -0.2794 0.1778)
						)
						(arc
							(start -0.2794 -0.1778)
							(mid -0.249642 -0.249642)
							(end -0.1778 -0.2794)
						)
						(arc
							(start 0.1778 -0.2794)
							(mid 0.249642 -0.249642)
							(end 0.2794 -0.1778)
						)
						(arc
							(start 0.2794 0.1778)
							(mid 0.249642 0.249642)
							(end 0.1778 0.2794)
						)
					)
					(width 0)
					(fill yes)
				)
			)
		)
		(pad "2" smd custom
			(at 0 0.4445 90)
			(size 0.1397 0.1397)
			(layers "B.Cu" "B.Mask" "B.Paste")
			(net "BMC_RGMII_C2_C3_D1_D2_E6")
			(options
				(clearance outline)
				(anchor circle)
			)
			(primitives
				(gr_poly
					(pts
						(arc
							(start -0.1778 0.2794)
							(mid -0.249642 0.249642)
							(end -0.2794 0.1778)
						)
						(arc
							(start -0.2794 -0.1778)
							(mid -0.249642 -0.249642)
							(end -0.1778 -0.2794)
						)
						(arc
							(start 0.1778 -0.2794)
							(mid 0.249642 -0.249642)
							(end 0.2794 -0.1778)
						)
						(arc
							(start 0.2794 0.1778)
							(mid 0.249642 0.249642)
							(end 0.1778 0.2794)
						)
					)
					(width 0)
					(fill yes)
				)
			)
		)
	)
	(footprint ""
		(layer "B.Cu")
		(at 26.079196 -136.099296 90)
		(property "Reference" "C64"
			(at 0 0 90)
			(layer "B.SilkS")
			(hide yes)
			(effects
				(font
					(size 1.27 1.27)
				)
				(justify mirror)
			)
		)
		(property "Value" "SC1U16V3KX-5GP"
			(at 0 -2.8194 90)
			(unlocked yes)
			(layer "B.Fab")
			(hide yes)
			(effects
				(font
					(size 1.016 1.016)
					(thickness 0.1524)
				)
				(justify mirror)
			)
		)
		(property "Device Type" "C603H36"
			(at 0 -4.3434 90)
			(unlocked yes)
			(layer "B.Fab")
			(hide yes)
			(effects
				(font
					(size 1.016 1.016)
					(thickness 0.1524)
				)
				(justify mirror)
			)
		)
		(duplicate_pad_numbers_are_jumpers no)
		(fp_line
			(start -0.508 0)
			(end 0.508 0)
			(stroke
				(width 0.2032)
				(type default)
			)
			(layer "B.SilkS")
		)
		(fp_rect
			(start 0.5842 1.3335)
			(end -0.5842 -1.3335)
			(stroke
				(width 0)
				(type default)
			)
			(fill no)
			(layer "B.CrtYd")
		)
		(fp_rect
			(start 0.5842 1.3335)
			(end -0.5842 -1.3335)
			(stroke
				(width 0)
				(type default)
			)
			(fill no)
			(layer "B.Fab")
		)
		(pad "1" smd custom
			(at 0 -0.762 270)
			(size 0.2159 0.2159)
			(layers "B.Cu" "B.Mask" "B.Paste")
			(net "P2V5_STBY")
			(options
				(clearance outline)
				(anchor circle)
			)
			(primitives
				(gr_poly
					(pts
						(arc
							(start -0.3302 0.4318)
							(mid -0.402042 0.402042)
							(end -0.4318 0.3302)
						)
						(arc
							(start -0.4318 -0.3302)
							(mid -0.402042 -0.402042)
							(end -0.3302 -0.4318)
						)
						(arc
							(start 0.3302 -0.4318)
							(mid 0.402042 -0.402042)
							(end 0.4318 -0.3302)
						)
						(arc
							(start 0.4318 0.3302)
							(mid 0.402042 0.402042)
							(end 0.3302 0.4318)
						)
					)
					(width 0)
					(fill yes)
				)
			)
		)
		(pad "2" smd custom
			(at 0 0.762 270)
			(size 0.2159 0.2159)
			(layers "B.Cu" "B.Mask" "B.Paste")
			(net "GND")
			(options
				(clearance outline)
				(anchor circle)
			)
			(primitives
				(gr_poly
					(pts
						(arc
							(start -0.3302 0.4318)
							(mid -0.402042 0.402042)
							(end -0.4318 0.3302)
						)
						(arc
							(start -0.4318 -0.3302)
							(mid -0.402042 -0.402042)
							(end -0.3302 -0.4318)
						)
						(arc
							(start 0.3302 -0.4318)
							(mid 0.402042 -0.402042)
							(end 0.4318 -0.3302)
						)
						(arc
							(start 0.4318 0.3302)
							(mid 0.402042 0.402042)
							(end 0.3302 0.4318)
						)
					)
					(width 0)
					(fill yes)
				)
			)
		)
	)
	(footprint ""
		(layer "B.Cu")
		(at 20.591272 -129.074164 180)
		(property "Reference" "R252"
			(at 0 0 0)
			(layer "B.SilkS")
			(hide yes)
			(effects
				(font
					(size 1.27 1.27)
				)
				(justify mirror)
			)
		)
		(property "Value" "120R2F-GP"
			(at -0.064008 -3.993896 180)
			(unlocked yes)
			(layer "B.Fab")
			(hide yes)
			(effects
				(font
					(size 1.016 1.016)
					(thickness 0.1524)
				)
				(justify mirror)
			)
		)
		(property "Device Type" "R402H16"
			(at -0.064008 -5.517896 180)
			(unlocked yes)
			(layer "B.Fab")
			(hide yes)
			(effects
				(font
					(size 1.016 1.016)
					(thickness 0.1524)
				)
				(justify mirror)
			)
		)
		(duplicate_pad_numbers_are_jumpers no)
		(fp_line
			(start 0.508 -0.9398)
			(end 0.508 0.9398)
			(stroke
				(width 0.1524)
				(type default)
			)
			(layer "B.SilkS")
		)
		(fp_line
			(start -0.508 -0.9398)
			(end 0.508 -0.9398)
			(stroke
				(width 0.1524)
				(type default)
			)
			(layer "B.SilkS")
		)
		(fp_rect
			(start 0.508 0.9398)
			(end -0.508 -0.9398)
			(stroke
				(width 0)
				(type default)
			)
			(fill no)
			(layer "B.CrtYd")
		)
		(fp_rect
			(start 0.508 0.9398)
			(end -0.508 -0.9398)
			(stroke
				(width 0)
				(type default)
			)
			(fill no)
			(layer "B.Fab")
		)
		(pad "1" smd custom
			(at 0 -0.4445)
			(size 0.1397 0.1397)
			(layers "B.Cu" "B.Mask" "B.Paste")
			(net "GND")
			(options
				(clearance outline)
				(anchor circle)
			)
			(primitives
				(gr_poly
					(pts
						(arc
							(start -0.1778 0.2794)
							(mid -0.249642 0.249642)
							(end -0.2794 0.1778)
						)
						(arc
							(start -0.2794 -0.1778)
							(mid -0.249642 -0.249642)
							(end -0.1778 -0.2794)
						)
						(arc
							(start 0.1778 -0.2794)
							(mid 0.249642 -0.249642)
							(end 0.2794 -0.1778)
						)
						(arc
							(start 0.2794 0.1778)
							(mid 0.249642 0.249642)
							(end 0.1778 0.2794)
						)
					)
					(width 0)
					(fill yes)
				)
			)
		)
		(pad "2" smd custom
			(at 0 0.4445)
			(size 0.1397 0.1397)
			(layers "B.Cu" "B.Mask" "B.Paste")
			(net "MEMA_9")
			(options
				(clearance outline)
				(anchor circle)
			)
			(primitives
				(gr_poly
					(pts
						(arc
							(start -0.1778 0.2794)
							(mid -0.249642 0.249642)
							(end -0.2794 0.1778)
						)
						(arc
							(start -0.2794 -0.1778)
							(mid -0.249642 -0.249642)
							(end -0.1778 -0.2794)
						)
						(arc
							(start 0.1778 -0.2794)
							(mid 0.249642 -0.249642)
							(end 0.2794 -0.1778)
						)
						(arc
							(start 0.2794 0.1778)
							(mid 0.249642 0.249642)
							(end 0.1778 0.2794)
						)
					)
					(width 0)
					(fill yes)
				)
			)
		)
	)
	(footprint ""
		(layer "B.Cu")
		(at 59.5884 -161.0106 -90)
		(property "Reference" "C119"
			(at 0 0 90)
			(layer "B.SilkS")
			(hide yes)
			(effects
				(font
					(size 1.27 1.27)
				)
				(justify mirror)
			)
		)
		(property "Value" "SCD1U25V2KX-2-GP"
			(at -1.1811 -2.7051 270)
			(unlocked yes)
			(layer "B.Fab")
			(hide yes)
			(effects
				(font
					(size 1.016 1.016)
					(thickness 0.1524)
				)
				(justify mirror)
			)
		)
		(property "Device Type" "C402H22"
			(at -1.1811 -4.2291 270)
			(unlocked yes)
			(layer "B.Fab")
			(hide yes)
			(effects
				(font
					(size 1.016 1.016)
					(thickness 0.1524)
				)
				(justify mirror)
			)
		)
		(duplicate_pad_numbers_are_jumpers no)
		(fp_rect
			(start 0.4318 0.9525)
			(end -0.4318 -0.9525)
			(stroke
				(width 0)
				(type default)
			)
			(fill no)
			(layer "B.CrtYd")
		)
		(fp_rect
			(start 0.4318 0.9525)
			(end -0.4318 -0.9525)
			(stroke
				(width 0)
				(type default)
			)
			(fill no)
			(layer "B.Fab")
		)
		(pad "1" smd custom
			(at 0 -0.4445 90)
			(size 0.1524 0.1524)
			(layers "B.Cu" "B.Mask" "B.Paste")
			(net "ADC_P1V8")
			(options
				(clearance outline)
				(anchor circle)
			)
			(primitives
				(gr_poly
					(pts
						(arc
							(start 0.3048 0.2032)
							(mid 0.275042 0.275042)
							(end 0.2032 0.3048)
						)
						(arc
							(start -0.2032 0.3048)
							(mid -0.275042 0.275042)
							(end -0.3048 0.2032)
						)
						(arc
							(start -0.3048 -0.2032)
							(mid -0.275042 -0.275042)
							(end -0.2032 -0.3048)
						)
						(arc
							(start 0.2032 -0.3048)
							(mid 0.275042 -0.275042)
							(end 0.3048 -0.2032)
						)
					)
					(width 0)
					(fill yes)
				)
			)
		)
		(pad "2" smd custom
			(at 0 0.4445 90)
			(size 0.1524 0.1524)
			(layers "B.Cu" "B.Mask" "B.Paste")
			(net "GND")
			(options
				(clearance outline)
				(anchor circle)
			)
			(primitives
				(gr_poly
					(pts
						(arc
							(start 0.3048 0.2032)
							(mid 0.275042 0.275042)
							(end 0.2032 0.3048)
						)
						(arc
							(start -0.2032 0.3048)
							(mid -0.275042 0.275042)
							(end -0.3048 0.2032)
						)
						(arc
							(start -0.3048 -0.2032)
							(mid -0.275042 -0.275042)
							(end -0.2032 -0.3048)
						)
						(arc
							(start 0.2032 -0.3048)
							(mid 0.275042 -0.275042)
							(end 0.3048 -0.2032)
						)
					)
					(width 0)
					(fill yes)
				)
			)
		)
	)
)
